#ISCELL
  logical_power design_note *
  *
#ISCELL
  pure_quanta quanta_title_block_c *
  *
#CELL
  pure_quanta q_res *
  page189_i100
#ISCELL
  standard offpage *
  page189_i101
#ISCELL
  standard offpage *
  page189_i102
#ISCELL
  standard offpage *
  page189_i103
#ISCELL
  standard offpage *
  page189_i104
#ISCELL
  logical_power universal_gnd *
  page189_i105
#CELL
  pure_quanta q_res *
  page189_i106
#CELL
  pure_quanta q_res *
  page189_i107
#ISCELL
  logical_power universal_gnd *
  page189_i108
#CELL
  pure_quanta q_res *
  page189_i109
#ISCELL
  logical_power universal_gnd *
  page189_i110
#ISCELL
  standard offpage *
  page189_i111
#ISCELL
  logical_power universal_power *
  page189_i112
#CELL
  pure_quanta q_res *
  page189_i113
#CELL
  pure_quanta q_res *
  page189_i114
#CELL
  pure_quanta sw_pushbutton4p_24 *
  page189_i122
#CELL
  pure_quanta q_res *
  page189_i123
#ISCELL
  logical_power universal_gnd *
  page189_i124
#ISCELL
  standard offpage *
  page189_i125
#ISCELL
  logical_power universal_power *
  page189_i126
#CELL
  pure_quanta q_res *
  page189_i127
#CELL
  pure_quanta q_cap *
  page189_i128
#ISCELL
  logical_power universal_gnd *
  page189_i129
#ISCELL
  standard offpage *
  page189_i130
#ISCELL
  standard offpage *
  page189_i131
#CELL
  pure_quanta q_res *
  page189_i132
#CELL
  pure_quanta q_res *
  page189_i133
#CELL
  pure_quanta conn14_210hp207gbr1 *
  page189_i134
#CELL
  pure_quanta q_res *
  page189_i86
#CELL
  pure_quanta q_res *
  page189_i87
#CELL
  pure_quanta q_res *
  page189_i88
#CELL
  pure_quanta q_res *
  page189_i89
#ISCELL
  logical_power universal_power *
  page189_i90
#ISCELL
  logical_power universal_power *
  page189_i92
#CELL
  pure_quanta q_res *
  page189_i93
#ISCELL
  logical_power universal_gnd *
  page189_i98
#ISCELL
  logical_power universal_power *
  page189_i99
